(kicad_pcb
	(version 20260206)
	(generator "pcbnew")
	(generator_version "10.0")
	(general
		(thickness 1.6)
		(legacy_teardrops no)
	)
	(paper "A4")
	(title_block
		(title "04192023_DAF0TMB3IC0_F0TG_MB_C_brd_V02_OCP.brd")
		(comment 1 "Grand Teton / footprints 6743-6750 of 8354")
	)
	(layers
		(0 "F.Cu" signal "TOP")
		(4 "In1.Cu" signal "GND")
		(6 "In2.Cu" signal "IN1")
		(8 "In3.Cu" signal "GND1")
		(10 "In4.Cu" signal "IN2")
		(12 "In5.Cu" signal "GND2")
		(14 "In6.Cu" signal "IN3")
		(16 "In7.Cu" signal "GND3")
		(18 "In8.Cu" signal "VCC")
		(20 "In9.Cu" signal "VCC1")
		(22 "In10.Cu" signal "GND4")
		(24 "In11.Cu" signal "IN4")
		(26 "In12.Cu" signal "GND5")
		(28 "In13.Cu" signal "IN5")
		(30 "In14.Cu" signal "GND6")
		(32 "In15.Cu" signal "IN6")
		(34 "In16.Cu" signal "GND7")
		(2 "B.Cu" signal "BOTTOM")
		(9 "F.Adhes" user "F.Adhesive")
		(11 "B.Adhes" user "B.Adhesive")
		(13 "F.Paste" user "Package Geometry/Pastemask Top")
		(15 "B.Paste" user "Package Geometry/Pastemask Bottom")
		(5 "F.SilkS" user "Ref Des/Silkscreen Top")
		(7 "B.SilkS" user "Ref Des/Silkscreen Bottom")
		(1 "F.Mask" user "Board Geometry/Soldermask Top")
		(3 "B.Mask" user "Board Geometry/Soldermask Bottom")
		(17 "Dwgs.User" user "User.Drawings")
		(19 "Cmts.User" user "User.Comments")
		(21 "Eco1.User" user "User.Eco1")
		(23 "Eco2.User" user "User.Eco2")
		(25 "Edge.Cuts" user "Board Geometry/Outline")
		(27 "Margin" user)
		(31 "F.CrtYd" user "Package Geometry/Place Bound Top")
		(29 "B.CrtYd" user "Package Geometry/Place Bound Bottom")
		(35 "F.Fab" user "Ref Des/Assembly Top")
		(33 "B.Fab" user "Ref Des/Assembly Bottom")
	)
	(footprint ""
		(layer "B.Cu")
		(at 149.900386 -314.47105 180)
		(property "Reference" "C237"
			(at 0 0 0)
			(layer "B.SilkS")
			(hide yes)
			(effects
				(font
					(size 1.27 1.27)
				)
				(justify mirror)
			)
		)
		(property "Value" ""
			(at 0 0 0)
			(layer "B.Fab")
			(effects
				(font
					(size 1.27 1.27)
				)
				(justify mirror)
			)
		)
		(duplicate_pad_numbers_are_jumpers no)
		(fp_line
			(start 0.7874 0.4064)
			(end 0.7874 -0.4064)
			(stroke
				(width 0.1524)
				(type default)
			)
			(layer "B.SilkS")
		)
		(fp_line
			(start 0.7874 -0.4064)
			(end -0.7874 -0.4064)
			(stroke
				(width 0.1524)
				(type default)
			)
			(layer "B.SilkS")
		)
		(fp_line
			(start -0.7874 0.4064)
			(end 0.7874 0.4064)
			(stroke
				(width 0.1524)
				(type default)
			)
			(layer "B.SilkS")
		)
		(fp_line
			(start -0.7874 -0.4064)
			(end -0.7874 0.4064)
			(stroke
				(width 0.1524)
				(type default)
			)
			(layer "B.SilkS")
		)
		(fp_line
			(start 0.67945 0.3048)
			(end 0.67945 -0.305054)
			(stroke
				(width 0.1)
				(type default)
			)
			(layer "B.Fab")
		)
		(fp_line
			(start 0.67945 -0.305054)
			(end 0.12065 -0.305054)
			(stroke
				(width 0.1)
				(type default)
			)
			(layer "B.Fab")
		)
		(fp_line
			(start 0.12065 0.3048)
			(end 0.67945 0.3048)
			(stroke
				(width 0.1)
				(type default)
			)
			(layer "B.Fab")
		)
		(fp_line
			(start 0.12065 0.2794)
			(end 0.12065 0.3048)
			(stroke
				(width 0.1)
				(type default)
			)
			(layer "B.Fab")
		)
		(fp_line
			(start 0.12065 -0.2794)
			(end -0.12065 -0.2794)
			(stroke
				(width 0.1)
				(type default)
			)
			(layer "B.Fab")
		)
		(fp_line
			(start 0.12065 -0.305054)
			(end 0.12065 -0.2794)
			(stroke
				(width 0.1)
				(type default)
			)
			(layer "B.Fab")
		)
		(fp_line
			(start -0.120396 0.3048)
			(end -0.120396 0.2794)
			(stroke
				(width 0.1)
				(type default)
			)
			(layer "B.Fab")
		)
		(fp_line
			(start -0.120396 0.2794)
			(end 0.12065 0.2794)
			(stroke
				(width 0.1)
				(type default)
			)
			(layer "B.Fab")
		)
		(fp_line
			(start -0.12065 -0.2794)
			(end -0.12065 -0.3048)
			(stroke
				(width 0.1)
				(type default)
			)
			(layer "B.Fab")
		)
		(fp_line
			(start -0.12065 -0.3048)
			(end -0.67945 -0.3048)
			(stroke
				(width 0.1)
				(type default)
			)
			(layer "B.Fab")
		)
		(fp_line
			(start -0.67945 0.3048)
			(end -0.120396 0.3048)
			(stroke
				(width 0.1)
				(type default)
			)
			(layer "B.Fab")
		)
		(fp_line
			(start -0.67945 -0.3048)
			(end -0.67945 0.3048)
			(stroke
				(width 0.1)
				(type default)
			)
			(layer "B.Fab")
		)
		(pad "1" smd circle
			(at 0.40005 0)
			(size 0 0)
			(layers "B.Cu" "B.Mask" "B.Paste")
			(net "XTAL_CPU1_X48M_X2_R")
		)
		(pad "2" smd circle
			(at -0.40005 0)
			(size 0 0)
			(layers "B.Cu" "B.Mask" "B.Paste")
			(net "GND")
		)
	)
	(footprint ""
		(layer "B.Cu")
		(at 288.346896 -349.381572 -90)
		(property "Reference" "PR104"
			(at 0 0 90)
			(layer "B.SilkS")
			(hide yes)
			(effects
				(font
					(size 1.27 1.27)
				)
				(justify mirror)
			)
		)
		(property "Value" ""
			(at 0 0 90)
			(layer "B.Fab")
			(effects
				(font
					(size 1.27 1.27)
				)
				(justify mirror)
			)
		)
		(duplicate_pad_numbers_are_jumpers no)
		(fp_line
			(start -0.7874 0.4064)
			(end 0.7874 0.4064)
			(stroke
				(width 0.1524)
				(type default)
			)
			(layer "B.SilkS")
		)
		(fp_line
			(start 0.7874 0.4064)
			(end 0.7874 -0.4064)
			(stroke
				(width 0.1524)
				(type default)
			)
			(layer "B.SilkS")
		)
		(fp_line
			(start -0.7874 -0.4064)
			(end -0.7874 0.4064)
			(stroke
				(width 0.1524)
				(type default)
			)
			(layer "B.SilkS")
		)
		(fp_line
			(start 0.7874 -0.4064)
			(end -0.7874 -0.4064)
			(stroke
				(width 0.1524)
				(type default)
			)
			(layer "B.SilkS")
		)
		(fp_line
			(start -0.67945 0.3048)
			(end -0.120396 0.3048)
			(stroke
				(width 0.1)
				(type default)
			)
			(layer "B.Fab")
		)
		(fp_line
			(start -0.120396 0.3048)
			(end -0.120396 0.2794)
			(stroke
				(width 0.1)
				(type default)
			)
			(layer "B.Fab")
		)
		(fp_line
			(start 0.12065 0.3048)
			(end 0.67945 0.3048)
			(stroke
				(width 0.1)
				(type default)
			)
			(layer "B.Fab")
		)
		(fp_line
			(start 0.67945 0.3048)
			(end 0.67945 -0.305054)
			(stroke
				(width 0.1)
				(type default)
			)
			(layer "B.Fab")
		)
		(fp_line
			(start -0.120396 0.2794)
			(end 0.12065 0.2794)
			(stroke
				(width 0.1)
				(type default)
			)
			(layer "B.Fab")
		)
		(fp_line
			(start 0.12065 0.2794)
			(end 0.12065 0.3048)
			(stroke
				(width 0.1)
				(type default)
			)
			(layer "B.Fab")
		)
		(fp_line
			(start -0.12065 -0.2794)
			(end -0.12065 -0.3048)
			(stroke
				(width 0.1)
				(type default)
			)
			(layer "B.Fab")
		)
		(fp_line
			(start 0.12065 -0.2794)
			(end -0.12065 -0.2794)
			(stroke
				(width 0.1)
				(type default)
			)
			(layer "B.Fab")
		)
		(fp_line
			(start -0.67945 -0.3048)
			(end -0.67945 0.3048)
			(stroke
				(width 0.1)
				(type default)
			)
			(layer "B.Fab")
		)
		(fp_line
			(start -0.12065 -0.3048)
			(end -0.67945 -0.3048)
			(stroke
				(width 0.1)
				(type default)
			)
			(layer "B.Fab")
		)
		(fp_line
			(start 0.12065 -0.305054)
			(end 0.12065 -0.2794)
			(stroke
				(width 0.1)
				(type default)
			)
			(layer "B.Fab")
		)
		(fp_line
			(start 0.67945 -0.305054)
			(end 0.12065 -0.305054)
			(stroke
				(width 0.1)
				(type default)
			)
			(layer "B.Fab")
		)
		(pad "1" smd circle
			(at 0.40005 0 90)
			(size 0 0)
			(layers "B.Cu" "B.Mask" "B.Paste")
			(net "PVDDIO_P0_VOS2")
		)
		(pad "2" smd circle
			(at -0.40005 0 90)
			(size 0 0)
			(layers "B.Cu" "B.Mask" "B.Paste")
			(net "PVDDIO_P0")
		)
	)
	(footprint ""
		(layer "B.Cu")
		(at 215.0618 -337.312)
		(property "Reference" "R779"
			(at 0 0 0)
			(layer "B.SilkS")
			(hide yes)
			(effects
				(font
					(size 1.27 1.27)
				)
				(justify mirror)
			)
		)
		(property "Value" ""
			(at 0 0 0)
			(layer "B.Fab")
			(effects
				(font
					(size 1.27 1.27)
				)
				(justify mirror)
			)
		)
		(duplicate_pad_numbers_are_jumpers no)
		(fp_line
			(start -0.32512 -0.175006)
			(end -0.32512 0.175006)
			(stroke
				(width 0.1)
				(type default)
			)
			(layer "B.Fab")
		)
		(fp_line
			(start -0.32512 0.175006)
			(end 0.32512 0.175006)
			(stroke
				(width 0.1)
				(type default)
			)
			(layer "B.Fab")
		)
		(fp_line
			(start 0.32512 -0.175006)
			(end -0.32512 -0.175006)
			(stroke
				(width 0.1)
				(type default)
			)
			(layer "B.Fab")
		)
		(fp_line
			(start 0.32512 0.175006)
			(end 0.32512 -0.175006)
			(stroke
				(width 0.1)
				(type default)
			)
			(layer "B.Fab")
		)
		(pad "1" smd rect
			(at 0.2667 0 180)
			(size 0.3048 0.381)
			(layers "B.Cu" "B.Mask" "B.Paste")
			(net "SMB_RT_CPU1_P1_R_SCL")
		)
		(pad "2" smd rect
			(at -0.2667 0)
			(size 0.3048 0.381)
			(layers "B.Cu" "B.Mask" "B.Paste")
			(net "SMB_RT_CPU1_P1_R2_SCL")
		)
	)
	(footprint ""
		(layer "B.Cu")
		(at 106.466386 -266.005564)
		(property "Reference" "C2287"
			(at 0 0 0)
			(layer "B.SilkS")
			(hide yes)
			(effects
				(font
					(size 1.27 1.27)
				)
				(justify mirror)
			)
		)
		(property "Value" ""
			(at 0 0 0)
			(layer "B.Fab")
			(effects
				(font
					(size 1.27 1.27)
				)
				(justify mirror)
			)
		)
		(duplicate_pad_numbers_are_jumpers no)
		(fp_line
			(start -0.7874 -0.4064)
			(end -0.7874 0.4064)
			(stroke
				(width 0.1524)
				(type default)
			)
			(layer "B.SilkS")
		)
		(fp_line
			(start -0.7874 0.4064)
			(end 0.7874 0.4064)
			(stroke
				(width 0.1524)
				(type default)
			)
			(layer "B.SilkS")
		)
		(fp_line
			(start 0.7874 -0.4064)
			(end -0.7874 -0.4064)
			(stroke
				(width 0.1524)
				(type default)
			)
			(layer "B.SilkS")
		)
		(fp_line
			(start 0.7874 0.4064)
			(end 0.7874 -0.4064)
			(stroke
				(width 0.1524)
				(type default)
			)
			(layer "B.SilkS")
		)
		(fp_line
			(start -0.67945 -0.3048)
			(end -0.67945 0.3048)
			(stroke
				(width 0.1)
				(type default)
			)
			(layer "B.Fab")
		)
		(fp_line
			(start -0.67945 0.3048)
			(end -0.120396 0.3048)
			(stroke
				(width 0.1)
				(type default)
			)
			(layer "B.Fab")
		)
		(fp_line
			(start -0.12065 -0.3048)
			(end -0.67945 -0.3048)
			(stroke
				(width 0.1)
				(type default)
			)
			(layer "B.Fab")
		)
		(fp_line
			(start -0.12065 -0.2794)
			(end -0.12065 -0.3048)
			(stroke
				(width 0.1)
				(type default)
			)
			(layer "B.Fab")
		)
		(fp_line
			(start -0.120396 0.2794)
			(end 0.12065 0.2794)
			(stroke
				(width 0.1)
				(type default)
			)
			(layer "B.Fab")
		)
		(fp_line
			(start -0.120396 0.3048)
			(end -0.120396 0.2794)
			(stroke
				(width 0.1)
				(type default)
			)
			(layer "B.Fab")
		)
		(fp_line
			(start 0.12065 -0.305054)
			(end 0.12065 -0.2794)
			(stroke
				(width 0.1)
				(type default)
			)
			(layer "B.Fab")
		)
		(fp_line
			(start 0.12065 -0.2794)
			(end -0.12065 -0.2794)
			(stroke
				(width 0.1)
				(type default)
			)
			(layer "B.Fab")
		)
		(fp_line
			(start 0.12065 0.2794)
			(end 0.12065 0.3048)
			(stroke
				(width 0.1)
				(type default)
			)
			(layer "B.Fab")
		)
		(fp_line
			(start 0.12065 0.3048)
			(end 0.67945 0.3048)
			(stroke
				(width 0.1)
				(type default)
			)
			(layer "B.Fab")
		)
		(fp_line
			(start 0.67945 -0.305054)
			(end 0.12065 -0.305054)
			(stroke
				(width 0.1)
				(type default)
			)
			(layer "B.Fab")
		)
		(fp_line
			(start 0.67945 0.3048)
			(end 0.67945 -0.305054)
			(stroke
				(width 0.1)
				(type default)
			)
			(layer "B.Fab")
		)
		(pad "1" smd circle
			(at 0.40005 0 180)
			(size 0 0)
			(layers "B.Cu" "B.Mask" "B.Paste")
			(net "PVDD11_S3_P1")
		)
		(pad "2" smd circle
			(at -0.40005 0 180)
			(size 0 0)
			(layers "B.Cu" "B.Mask" "B.Paste")
			(net "GND")
		)
	)
	(footprint ""
		(layer "B.Cu")
		(at 241.756692 -420.80688 -90)
		(property "Reference" "R9000"
			(at 0 0 90)
			(layer "B.SilkS")
			(hide yes)
			(effects
				(font
					(size 1.27 1.27)
				)
				(justify mirror)
			)
		)
		(property "Value" ""
			(at 0 0 90)
			(layer "B.Fab")
			(effects
				(font
					(size 1.27 1.27)
				)
				(justify mirror)
			)
		)
		(duplicate_pad_numbers_are_jumpers no)
		(fp_line
			(start -0.7874 0.4064)
			(end 0.7874 0.4064)
			(stroke
				(width 0.1524)
				(type default)
			)
			(layer "B.SilkS")
		)
		(fp_line
			(start 0.7874 0.4064)
			(end 0.7874 -0.4064)
			(stroke
				(width 0.1524)
				(type default)
			)
			(layer "B.SilkS")
		)
		(fp_line
			(start -0.7874 -0.4064)
			(end -0.7874 0.4064)
			(stroke
				(width 0.1524)
				(type default)
			)
			(layer "B.SilkS")
		)
		(fp_line
			(start 0.7874 -0.4064)
			(end -0.7874 -0.4064)
			(stroke
				(width 0.1524)
				(type default)
			)
			(layer "B.SilkS")
		)
		(fp_line
			(start -0.67945 0.3048)
			(end -0.120396 0.3048)
			(stroke
				(width 0.1)
				(type default)
			)
			(layer "B.Fab")
		)
		(fp_line
			(start -0.120396 0.3048)
			(end -0.120396 0.2794)
			(stroke
				(width 0.1)
				(type default)
			)
			(layer "B.Fab")
		)
		(fp_line
			(start 0.12065 0.3048)
			(end 0.67945 0.3048)
			(stroke
				(width 0.1)
				(type default)
			)
			(layer "B.Fab")
		)
		(fp_line
			(start 0.67945 0.3048)
			(end 0.67945 -0.305054)
			(stroke
				(width 0.1)
				(type default)
			)
			(layer "B.Fab")
		)
		(fp_line
			(start -0.120396 0.2794)
			(end 0.12065 0.2794)
			(stroke
				(width 0.1)
				(type default)
			)
			(layer "B.Fab")
		)
		(fp_line
			(start 0.12065 0.2794)
			(end 0.12065 0.3048)
			(stroke
				(width 0.1)
				(type default)
			)
			(layer "B.Fab")
		)
		(fp_line
			(start -0.12065 -0.2794)
			(end -0.12065 -0.3048)
			(stroke
				(width 0.1)
				(type default)
			)
			(layer "B.Fab")
		)
		(fp_line
			(start 0.12065 -0.2794)
			(end -0.12065 -0.2794)
			(stroke
				(width 0.1)
				(type default)
			)
			(layer "B.Fab")
		)
		(fp_line
			(start -0.67945 -0.3048)
			(end -0.67945 0.3048)
			(stroke
				(width 0.1)
				(type default)
			)
			(layer "B.Fab")
		)
		(fp_line
			(start -0.12065 -0.3048)
			(end -0.67945 -0.3048)
			(stroke
				(width 0.1)
				(type default)
			)
			(layer "B.Fab")
		)
		(fp_line
			(start 0.12065 -0.305054)
			(end 0.12065 -0.2794)
			(stroke
				(width 0.1)
				(type default)
			)
			(layer "B.Fab")
		)
		(fp_line
			(start 0.67945 -0.305054)
			(end 0.12065 -0.305054)
			(stroke
				(width 0.1)
				(type default)
			)
			(layer "B.Fab")
		)
		(pad "1" smd circle
			(at 0.40005 0 90)
			(size 0 0)
			(layers "B.Cu" "B.Mask" "B.Paste")
			(net "P3V3_AUX")
		)
		(pad "2" smd circle
			(at -0.40005 0 90)
			(size 0 0)
			(layers "B.Cu" "B.Mask" "B.Paste")
			(net "FM_FAN_PWR_EN")
		)
	)
	(footprint ""
		(layer "B.Cu")
		(at 349.099886 -416.899344 90)
		(property "Reference" "C6561"
			(at 0 0 90)
			(layer "B.SilkS")
			(hide yes)
			(effects
				(font
					(size 1.27 1.27)
				)
				(justify mirror)
			)
		)
		(property "Value" ""
			(at 0 0 90)
			(layer "B.Fab")
			(effects
				(font
					(size 1.27 1.27)
				)
				(justify mirror)
			)
		)
		(duplicate_pad_numbers_are_jumpers no)
		(fp_line
			(start 0.299974 -0.150114)
			(end -0.299974 -0.150114)
			(stroke
				(width 0.1)
				(type default)
			)
			(layer "B.Fab")
		)
		(fp_line
			(start -0.299974 -0.150114)
			(end -0.299974 0.150114)
			(stroke
				(width 0.1)
				(type default)
			)
			(layer "B.Fab")
		)
		(fp_line
			(start 0.299974 0.150114)
			(end 0.299974 -0.150114)
			(stroke
				(width 0.1)
				(type default)
			)
			(layer "B.Fab")
		)
		(fp_line
			(start -0.299974 0.150114)
			(end 0.299974 0.150114)
			(stroke
				(width 0.1)
				(type default)
			)
			(layer "B.Fab")
		)
		(pad "1" smd rect
			(at 0.2667 0 270)
			(size 0.3048 0.381)
			(layers "B.Cu" "B.Mask" "B.Paste")
			(net "P5E_CPU0_P1_TX_BUF_C_DP<14>")
		)
		(pad "2" smd rect
			(at -0.2667 0 270)
			(size 0.3048 0.381)
			(layers "B.Cu" "B.Mask" "B.Paste")
			(net "P5E_CPU0_P1_TX_BUF_DP<14>")
		)
	)
	(footprint ""
		(layer "B.Cu")
		(at 288.29 -426.466 180)
		(property "Reference" "R2675"
			(at 0 0 0)
			(layer "B.SilkS")
			(hide yes)
			(effects
				(font
					(size 1.27 1.27)
				)
				(justify mirror)
			)
		)
		(property "Value" ""
			(at 0 0 0)
			(layer "B.Fab")
			(effects
				(font
					(size 1.27 1.27)
				)
				(justify mirror)
			)
		)
		(duplicate_pad_numbers_are_jumpers no)
		(fp_line
			(start 0.7874 0.4064)
			(end 0.7874 -0.4064)
			(stroke
				(width 0.1524)
				(type default)
			)
			(layer "B.SilkS")
		)
		(fp_line
			(start 0.7874 -0.4064)
			(end -0.7874 -0.4064)
			(stroke
				(width 0.1524)
				(type default)
			)
			(layer "B.SilkS")
		)
		(fp_line
			(start -0.7874 0.4064)
			(end 0.7874 0.4064)
			(stroke
				(width 0.1524)
				(type default)
			)
			(layer "B.SilkS")
		)
		(fp_line
			(start -0.7874 -0.4064)
			(end -0.7874 0.4064)
			(stroke
				(width 0.1524)
				(type default)
			)
			(layer "B.SilkS")
		)
		(fp_line
			(start 0.67945 0.3048)
			(end 0.67945 -0.305054)
			(stroke
				(width 0.1)
				(type default)
			)
			(layer "B.Fab")
		)
		(fp_line
			(start 0.67945 -0.305054)
			(end 0.12065 -0.305054)
			(stroke
				(width 0.1)
				(type default)
			)
			(layer "B.Fab")
		)
		(fp_line
			(start 0.12065 0.3048)
			(end 0.67945 0.3048)
			(stroke
				(width 0.1)
				(type default)
			)
			(layer "B.Fab")
		)
		(fp_line
			(start 0.12065 0.2794)
			(end 0.12065 0.3048)
			(stroke
				(width 0.1)
				(type default)
			)
			(layer "B.Fab")
		)
		(fp_line
			(start 0.12065 -0.2794)
			(end -0.12065 -0.2794)
			(stroke
				(width 0.1)
				(type default)
			)
			(layer "B.Fab")
		)
		(fp_line
			(start 0.12065 -0.305054)
			(end 0.12065 -0.2794)
			(stroke
				(width 0.1)
				(type default)
			)
			(layer "B.Fab")
		)
		(fp_line
			(start -0.120396 0.3048)
			(end -0.120396 0.2794)
			(stroke
				(width 0.1)
				(type default)
			)
			(layer "B.Fab")
		)
		(fp_line
			(start -0.120396 0.2794)
			(end 0.12065 0.2794)
			(stroke
				(width 0.1)
				(type default)
			)
			(layer "B.Fab")
		)
		(fp_line
			(start -0.12065 -0.2794)
			(end -0.12065 -0.3048)
			(stroke
				(width 0.1)
				(type default)
			)
			(layer "B.Fab")
		)
		(fp_line
			(start -0.12065 -0.3048)
			(end -0.67945 -0.3048)
			(stroke
				(width 0.1)
				(type default)
			)
			(layer "B.Fab")
		)
		(fp_line
			(start -0.67945 0.3048)
			(end -0.120396 0.3048)
			(stroke
				(width 0.1)
				(type default)
			)
			(layer "B.Fab")
		)
		(fp_line
			(start -0.67945 -0.3048)
			(end -0.67945 0.3048)
			(stroke
				(width 0.1)
				(type default)
			)
			(layer "B.Fab")
		)
		(pad "1" smd circle
			(at 0.40005 0)
			(size 0 0)
			(layers "B.Cu" "B.Mask" "B.Paste")
			(net "I3C_BMC_SWB_BUF_R_SCL")
		)
		(pad "2" smd circle
			(at -0.40005 0)
			(size 0 0)
			(layers "B.Cu" "B.Mask" "B.Paste")
			(net "I3C_BMC_SWB_BUF_SCL")
		)
	)
	(footprint ""
		(layer "B.Cu")
		(at 394.757402 -416.899344 90)
		(property "Reference" "C6611"
			(at 0 0 90)
			(layer "B.SilkS")
			(hide yes)
			(effects
				(font
					(size 1.27 1.27)
				)
				(justify mirror)
			)
		)
		(property "Value" ""
			(at 0 0 90)
			(layer "B.Fab")
			(effects
				(font
					(size 1.27 1.27)
				)
				(justify mirror)
			)
		)
		(duplicate_pad_numbers_are_jumpers no)
		(fp_line
			(start 0.299974 -0.150114)
			(end -0.299974 -0.150114)
			(stroke
				(width 0.1)
				(type default)
			)
			(layer "B.Fab")
		)
		(fp_line
			(start -0.299974 -0.150114)
			(end -0.299974 0.150114)
			(stroke
				(width 0.1)
				(type default)
			)
			(layer "B.Fab")
		)
		(fp_line
			(start 0.299974 0.150114)
			(end 0.299974 -0.150114)
			(stroke
				(width 0.1)
				(type default)
			)
			(layer "B.Fab")
		)
		(fp_line
			(start -0.299974 0.150114)
			(end 0.299974 0.150114)
			(stroke
				(width 0.1)
				(type default)
			)
			(layer "B.Fab")
		)
		(pad "1" smd rect
			(at 0.2667 0 270)
			(size 0.3048 0.381)
			(layers "B.Cu" "B.Mask" "B.Paste")
			(net "P5E_CPU0_P3_TX_BUF_C_DP<7>")
		)
		(pad "2" smd rect
			(at -0.2667 0 270)
			(size 0.3048 0.381)
			(layers "B.Cu" "B.Mask" "B.Paste")
			(net "P5E_CPU0_P3_TX_BUF_DP<7>")
		)
	)
)
